(kicad_pcb
	(version 20241229)
	(generator "pcbnew")
	(generator_version "9.0")
	(general
		(thickness 1.62)
		(legacy_teardrops no)
	)
	(paper "A3")
	(title_block
		(title "COM Express 7 Baseboard")
		(date "2025-02-04")
		(rev "1.1.2")
		(company "Antmicro Ltd")
		(comment 1 "www.antmicro.com")
		(comment 9 "footprints 591-596 of 802")
	)
	(layers
		(0 "F.Cu" signal)
		(4 "In1.Cu" signal)
		(6 "In2.Cu" signal)
		(8 "In3.Cu" signal)
		(10 "In4.Cu" signal)
		(12 "In5.Cu" signal)
		(14 "In6.Cu" signal)
		(2 "B.Cu" signal)
		(9 "F.Adhes" user "F.Adhesive")
		(11 "B.Adhes" user "B.Adhesive")
		(13 "F.Paste" user)
		(15 "B.Paste" user)
		(5 "F.SilkS" user "F.Silkscreen")
		(7 "B.SilkS" user "B.Silkscreen")
		(1 "F.Mask" user)
		(3 "B.Mask" user)
		(17 "Dwgs.User" user "User.Drawings")
		(19 "Cmts.User" user "User.Comments")
		(21 "Eco1.User" user "User.Eco1")
		(23 "Eco2.User" user "User.Eco2")
		(25 "Edge.Cuts" user)
		(27 "Margin" user)
		(31 "F.CrtYd" user "F.Courtyard")
		(29 "B.CrtYd" user "B.Courtyard")
		(35 "F.Fab" user)
		(33 "B.Fab" user)
	)
	(footprint "antmicro-footprints:R_0402_1005Metric"
		(layer "B.Cu")
		(at 123.4 97.86 180)
		(descr "Resistor SMD 0402")
		(tags "resistor SMD 0402")
		(property "Reference" "R1"
			(at -2.4 -0.45 0)
			(layer "B.SilkS")
			(effects
				(font
					(size 0.7 0.7)
					(thickness 0.15)
				)
				(justify left bottom mirror)
			)
		)
		(property "Value" "R_0R_0402"
			(at -1.011843 -1.772047 0)
			(layer "B.Fab")
			(effects
				(font
					(size 0.7 0.7)
					(thickness 0.15)
				)
				(justify left bottom mirror)
			)
		)
		(property "Datasheet" "https://industrial.panasonic.com/cdbs/www-data/pdf/RDA0000/AOA0000C301.pdf"
			(at 0 0 180)
			(layer "F.Fab")
			(hide yes)
			(effects
				(font
					(size 1.27 1.27)
					(thickness 0.15)
				)
			)
		)
		(property "Author" "Antmicro"
			(at 246.8 195.72 0)
			(layer "B.Fab")
			(hide yes)
			(effects
				(font
					(size 1 1)
					(thickness 0.15)
				)
				(justify mirror)
			)
		)
		(property "Current" "1A"
			(at 246.8 195.72 0)
			(layer "B.Fab")
			(hide yes)
			(effects
				(font
					(size 1 1)
					(thickness 0.15)
				)
				(justify mirror)
			)
		)
		(property "License" "Apache-2.0"
			(at 246.8 195.72 0)
			(layer "B.Fab")
			(hide yes)
			(effects
				(font
					(size 1 1)
					(thickness 0.15)
				)
				(justify mirror)
			)
		)
		(property "MPN" "ERJ2GE0R00X"
			(at 246.8 195.72 0)
			(layer "B.Fab")
			(hide yes)
			(effects
				(font
					(size 1 1)
					(thickness 0.15)
				)
				(justify mirror)
			)
		)
		(property "Manufacturer" "Panasonic"
			(at 246.8 195.72 0)
			(layer "B.Fab")
			(hide yes)
			(effects
				(font
					(size 1 1)
					(thickness 0.15)
				)
				(justify mirror)
			)
		)
		(property "Public" "False"
			(at 246.8 195.72 0)
			(layer "B.Fab")
			(hide yes)
			(effects
				(font
					(size 1 1)
					(thickness 0.15)
				)
				(justify mirror)
			)
		)
		(property "Tolerance" ""
			(at 246.8 195.72 0)
			(layer "B.Fab")
			(hide yes)
			(effects
				(font
					(size 1 1)
					(thickness 0.15)
				)
				(justify mirror)
			)
		)
		(property "Val" "0R"
			(at 246.8 195.72 0)
			(layer "B.Fab")
			(hide yes)
			(effects
				(font
					(size 1 1)
					(thickness 0.15)
				)
				(justify mirror)
			)
		)
		(sheetname "2xUSB3.0+RJ45")
		(sheetfile "usb3+rj45.kicad_sch")
		(attr smd)
		(fp_rect
			(start -0.925 0.47)
			(end 0.925 -0.47)
			(stroke
				(width 0.05)
				(type default)
			)
			(fill no)
			(layer "B.CrtYd")
		)
		(fp_rect
			(start -0.5 0.25)
			(end 0.5 -0.25)
			(stroke
				(width 0.15)
				(type solid)
			)
			(fill no)
			(layer "B.Fab")
		)
		(pad "1" smd roundrect
			(at -0.48 0 180)
			(size 0.59 0.64)
			(layers "B.Cu" "B.Mask" "B.Paste")
			(roundrect_rratio 0.25)
			(net 347 "/2xUSB3.0+RJ45/~{GBE0_ACT}")
			(pintype "passive")
			(teardrops
				(best_length_ratio 0.2)
				(max_length 1)
				(best_width_ratio 0.9)
				(max_width 2)
				(curved_edges yes)
				(filter_ratio 0.9)
				(enabled yes)
				(allow_two_segments yes)
				(prefer_zone_connections yes)
			)
		)
		(pad "2" smd roundrect
			(at 0.48 0 180)
			(size 0.59 0.64)
			(layers "B.Cu" "B.Mask" "B.Paste")
			(roundrect_rratio 0.25)
			(net 154 "Net-(J1A-LED_D1)")
			(pintype "passive")
			(teardrops
				(best_length_ratio 0.2)
				(max_length 1)
				(best_width_ratio 0.9)
				(max_width 2)
				(curved_edges yes)
				(filter_ratio 0.9)
				(enabled yes)
				(allow_two_segments yes)
				(prefer_zone_connections yes)
			)
		)
	)
	(footprint "antmicro-footprints:C_0402_1005Metric"
		(layer "B.Cu")
		(at 113.734999 76.725 180)
		(descr "Capacitor SMD 0402")
		(tags "capacitor SMD 0402")
		(property "Reference" "C32"
			(at 0.784999 -0.435 0)
			(layer "B.SilkS")
			(effects
				(font
					(size 0.7 0.7)
					(thickness 0.15)
				)
				(justify left bottom mirror)
			)
		)
		(property "Value" "C_100n_0402"
			(at -1.022927 -2.155213 0)
			(layer "B.Fab")
			(effects
				(font
					(size 0.7 0.7)
					(thickness 0.15)
				)
				(justify left bottom mirror)
			)
		)
		(property "Datasheet" "https://www.murata.com/products/productdetail?partno=GRM155R61H104KE14%23"
			(at 0 0 180)
			(layer "F.Fab")
			(hide yes)
			(effects
				(font
					(size 1.27 1.27)
					(thickness 0.15)
				)
			)
		)
		(property "Author" "Antmicro"
			(at 227.469998 153.45 0)
			(layer "B.Fab")
			(hide yes)
			(effects
				(font
					(size 1 1)
					(thickness 0.15)
				)
				(justify mirror)
			)
		)
		(property "Dielectric" "X5R"
			(at 227.469998 153.45 0)
			(layer "B.Fab")
			(hide yes)
			(effects
				(font
					(size 1 1)
					(thickness 0.15)
				)
				(justify mirror)
			)
		)
		(property "License" "Apache-2.0"
			(at 227.469998 153.45 0)
			(layer "B.Fab")
			(hide yes)
			(effects
				(font
					(size 1 1)
					(thickness 0.15)
				)
				(justify mirror)
			)
		)
		(property "MPN" "GRM155R61H104KE14D"
			(at 227.469998 153.45 0)
			(layer "B.Fab")
			(hide yes)
			(effects
				(font
					(size 1 1)
					(thickness 0.15)
				)
				(justify mirror)
			)
		)
		(property "Manufacturer" "Murata"
			(at 227.469998 153.45 0)
			(layer "B.Fab")
			(hide yes)
			(effects
				(font
					(size 1 1)
					(thickness 0.15)
				)
				(justify mirror)
			)
		)
		(property "Public" "False"
			(at 227.469998 153.45 0)
			(layer "B.Fab")
			(hide yes)
			(effects
				(font
					(size 1 1)
					(thickness 0.15)
				)
				(justify mirror)
			)
		)
		(property "Val" "100n"
			(at 227.469998 153.45 0)
			(layer "B.Fab")
			(hide yes)
			(effects
				(font
					(size 1 1)
					(thickness 0.15)
				)
				(justify mirror)
			)
		)
		(property "Voltage" "50V"
			(at 227.469998 153.45 0)
			(layer "B.Fab")
			(hide yes)
			(effects
				(font
					(size 1 1)
					(thickness 0.15)
				)
				(justify mirror)
			)
		)
		(sheetname "USB-C console")
		(sheetfile "usb-c_console.kicad_sch")
		(attr smd)
		(fp_rect
			(start -0.925 0.47)
			(end 0.925 -0.47)
			(stroke
				(width 0.05)
				(type default)
			)
			(fill no)
			(layer "B.CrtYd")
		)
		(fp_line
			(start 0.504 0.25)
			(end -0.494 0.25)
			(stroke
				(width 0.15)
				(type solid)
			)
			(layer "B.Fab")
		)
		(fp_line
			(start 0.504 -0.248)
			(end 0.504 0.25)
			(stroke
				(width 0.15)
				(type solid)
			)
			(layer "B.Fab")
		)
		(fp_line
			(start -0.494 0.25)
			(end -0.494 -0.248)
			(stroke
				(width 0.15)
				(type solid)
			)
			(layer "B.Fab")
		)
		(fp_line
			(start -0.494 -0.248)
			(end 0.504 -0.248)
			(stroke
				(width 0.15)
				(type solid)
			)
			(layer "B.Fab")
		)
		(pad "1" smd roundrect
			(at -0.48 0 180)
			(size 0.59 0.64)
			(layers "B.Cu" "B.Mask" "B.Paste")
			(roundrect_rratio 0.25)
			(net 1 "GND")
			(pintype "passive")
			(teardrops
				(best_length_ratio 0.2)
				(max_length 1)
				(best_width_ratio 0.9)
				(max_width 2)
				(curved_edges yes)
				(filter_ratio 0.9)
				(enabled yes)
				(allow_two_segments yes)
				(prefer_zone_connections yes)
			)
		)
		(pad "2" smd roundrect
			(at 0.48 0 180)
			(size 0.59 0.64)
			(layers "B.Cu" "B.Mask" "B.Paste")
			(roundrect_rratio 0.25)
			(net 57 "/USB-C console/FTDI_VCCIO")
			(pintype "passive")
			(teardrops
				(best_length_ratio 0.2)
				(max_length 1)
				(best_width_ratio 0.9)
				(max_width 2)
				(curved_edges yes)
				(filter_ratio 0.9)
				(enabled yes)
				(allow_two_segments yes)
				(prefer_zone_connections yes)
			)
		)
	)
	(footprint "antmicro-footprints:TP_SMD_0.75mm"
		(layer "B.Cu")
		(at 259.95 86.36 180)
		(property "Reference" "TP13"
			(at -3.1 -0.4 0)
			(layer "B.SilkS")
			(effects
				(font
					(size 0.7 0.7)
					(thickness 0.15)
				)
				(justify left bottom mirror)
			)
		)
		(property "Value" "TP_0.75mm_SMD"
			(at 0 -1.2 0)
			(layer "B.Fab")
			(effects
				(font
					(size 0.7 0.7)
					(thickness 0.15)
				)
				(justify left bottom mirror)
			)
		)
		(property "Author" "Antmicro"
			(at 519.9 172.72 0)
			(layer "B.Fab")
			(hide yes)
			(effects
				(font
					(size 1 1)
					(thickness 0.15)
				)
				(justify mirror)
			)
		)
		(property "License" "Apache-2.0"
			(at 519.9 172.72 0)
			(layer "B.Fab")
			(hide yes)
			(effects
				(font
					(size 1 1)
					(thickness 0.15)
				)
				(justify mirror)
			)
		)
		(property "MPN" ""
			(at 519.9 172.72 0)
			(layer "B.Fab")
			(hide yes)
			(effects
				(font
					(size 1 1)
					(thickness 0.15)
				)
				(justify mirror)
			)
		)
		(property "Manufacturer" ""
			(at 519.9 172.72 0)
			(layer "B.Fab")
			(hide yes)
			(effects
				(font
					(size 1 1)
					(thickness 0.15)
				)
				(justify mirror)
			)
		)
		(property "Public" "False"
			(at 519.9 172.72 0)
			(layer "B.Fab")
			(hide yes)
			(effects
				(font
					(size 1 1)
					(thickness 0.15)
				)
				(justify mirror)
			)
		)
		(sheetname "Misc")
		(sheetfile "misc.kicad_sch")
		(attr exclude_from_pos_files exclude_from_bom)
		(fp_circle
			(center 0 0)
			(end 0.475 0)
			(stroke
				(width 0.05)
				(type default)
			)
			(fill no)
			(layer "B.CrtYd")
		)
		(pad "1" smd circle
			(at 0 0 180)
			(size 0.75 0.75)
			(layers "B.Cu" "B.Mask")
			(net 705 "Net-(U24-GPIO1)")
			(pinfunction "1")
			(pintype "passive")
			(teardrops
				(best_length_ratio 0.4)
				(max_length 1)
				(best_width_ratio 0.9)
				(max_width 2)
				(curved_edges yes)
				(filter_ratio 0.9)
				(enabled yes)
				(allow_two_segments yes)
				(prefer_zone_connections yes)
			)
		)
	)
	(footprint "antmicro-footprints:R_0402_1005Metric"
		(layer "B.Cu")
		(at 146.05 169.16 -90)
		(descr "Resistor SMD 0402")
		(tags "resistor SMD 0402")
		(property "Reference" "R49"
			(at -3.9 13.5 90)
			(layer "B.SilkS")
			(effects
				(font
					(size 0.7 0.7)
					(thickness 0.15)
				)
				(justify left bottom mirror)
			)
		)
		(property "Value" "R_1k_0402"
			(at -1.011843 -1.772047 90)
			(layer "B.Fab")
			(effects
				(font
					(size 0.7 0.7)
					(thickness 0.15)
				)
				(justify left bottom mirror)
			)
		)
		(property "Datasheet" "https://www.bourns.com/docs/product-datasheets/cr.pdf"
			(at 0 0 270)
			(layer "F.Fab")
			(hide yes)
			(effects
				(font
					(size 1.27 1.27)
					(thickness 0.15)
				)
			)
		)
		(property "Author" "Antmicro"
			(at -23.11 315.21 0)
			(layer "B.Fab")
			(hide yes)
			(effects
				(font
					(size 1 1)
					(thickness 0.15)
				)
				(justify mirror)
			)
		)
		(property "License" "Apache-2.0"
			(at -23.11 315.21 0)
			(layer "B.Fab")
			(hide yes)
			(effects
				(font
					(size 1 1)
					(thickness 0.15)
				)
				(justify mirror)
			)
		)
		(property "MPN" "CR0402-FX-1001GLF"
			(at -23.11 315.21 0)
			(layer "B.Fab")
			(hide yes)
			(effects
				(font
					(size 1 1)
					(thickness 0.15)
				)
				(justify mirror)
			)
		)
		(property "Manufacturer" "Bourns"
			(at -23.11 315.21 0)
			(layer "B.Fab")
			(hide yes)
			(effects
				(font
					(size 1 1)
					(thickness 0.15)
				)
				(justify mirror)
			)
		)
		(property "Public" "False"
			(at -23.11 315.21 0)
			(layer "B.Fab")
			(hide yes)
			(effects
				(font
					(size 1 1)
					(thickness 0.15)
				)
				(justify mirror)
			)
		)
		(property "Tolerance" "1%"
			(at -23.11 315.21 0)
			(layer "B.Fab")
			(hide yes)
			(effects
				(font
					(size 1 1)
					(thickness 0.15)
				)
				(justify mirror)
			)
		)
		(property "Val" "1k"
			(at -23.11 315.21 0)
			(layer "B.Fab")
			(hide yes)
			(effects
				(font
					(size 1 1)
					(thickness 0.15)
				)
				(justify mirror)
			)
		)
		(sheetname "2xSFP+")
		(sheetfile "2xSFP+.kicad_sch")
		(attr smd)
		(fp_rect
			(start -0.925 0.47)
			(end 0.925 -0.47)
			(stroke
				(width 0.05)
				(type default)
			)
			(fill no)
			(layer "B.CrtYd")
		)
		(fp_rect
			(start -0.5 0.25)
			(end 0.5 -0.25)
			(stroke
				(width 0.15)
				(type solid)
			)
			(fill no)
			(layer "B.Fab")
		)
		(pad "1" smd roundrect
			(at -0.48 0 270)
			(size 0.59 0.64)
			(layers "B.Cu" "B.Mask" "B.Paste")
			(roundrect_rratio 0.25)
			(net 167 "Net-(J2A-RS0)")
			(pintype "passive")
			(teardrops
				(best_length_ratio 0.2)
				(max_length 1)
				(best_width_ratio 0.9)
				(max_width 2)
				(curved_edges yes)
				(filter_ratio 0.9)
				(enabled yes)
				(allow_two_segments yes)
				(prefer_zone_connections yes)
			)
		)
		(pad "2" smd roundrect
			(at 0.48 0 270)
			(size 0.59 0.64)
			(layers "B.Cu" "B.Mask" "B.Paste")
			(roundrect_rratio 0.25)
			(net 2 "+3V3")
			(pintype "passive")
			(teardrops
				(best_length_ratio 0.2)
				(max_length 1)
				(best_width_ratio 0.9)
				(max_width 2)
				(curved_edges yes)
				(filter_ratio 0.9)
				(enabled yes)
				(allow_two_segments yes)
				(prefer_zone_connections yes)
			)
		)
	)
	(footprint "antmicro-footprints:R_0402_1005Metric"
		(layer "B.Cu")
		(at 121.7 161.56)
		(descr "Resistor SMD 0402")
		(tags "resistor SMD 0402")
		(property "Reference" "R79"
			(at 0.85 0.45 0)
			(layer "B.SilkS")
			(effects
				(font
					(size 0.7 0.7)
					(thickness 0.15)
				)
				(justify right bottom mirror)
			)
		)
		(property "Value" "R_10k_0402"
			(at -1.011843 -1.772047 0)
			(layer "B.Fab")
			(effects
				(font
					(size 0.7 0.7)
					(thickness 0.15)
				)
				(justify right bottom mirror)
			)
		)
		(property "Datasheet" "https://www.bourns.com/docs/product-datasheets/cr.pdf"
			(at 0 0 0)
			(layer "F.Fab")
			(hide yes)
			(effects
				(font
					(size 1.27 1.27)
					(thickness 0.15)
				)
			)
		)
		(property "Author" "Antmicro"
			(at 0 0 0)
			(layer "B.Fab")
			(hide yes)
			(effects
				(font
					(size 1 1)
					(thickness 0.15)
				)
				(justify mirror)
			)
		)
		(property "License" "Apache-2.0"
			(at 0 0 0)
			(layer "B.Fab")
			(hide yes)
			(effects
				(font
					(size 1 1)
					(thickness 0.15)
				)
				(justify mirror)
			)
		)
		(property "MPN" "CR0402-FX-1002GLF"
			(at 0 0 0)
			(layer "B.Fab")
			(hide yes)
			(effects
				(font
					(size 1 1)
					(thickness 0.15)
				)
				(justify mirror)
			)
		)
		(property "Manufacturer" "Bourns"
			(at 0 0 0)
			(layer "B.Fab")
			(hide yes)
			(effects
				(font
					(size 1 1)
					(thickness 0.15)
				)
				(justify mirror)
			)
		)
		(property "Public" "False"
			(at 0 0 0)
			(layer "B.Fab")
			(hide yes)
			(effects
				(font
					(size 1 1)
					(thickness 0.15)
				)
				(justify mirror)
			)
		)
		(property "Tolerance" "1%"
			(at 0 0 0)
			(layer "B.Fab")
			(hide yes)
			(effects
				(font
					(size 1 1)
					(thickness 0.15)
				)
				(justify mirror)
			)
		)
		(property "Val" "10k"
			(at 0 0 0)
			(layer "B.Fab")
			(hide yes)
			(effects
				(font
					(size 1 1)
					(thickness 0.15)
				)
				(justify mirror)
			)
		)
		(sheetname "OCuLink")
		(sheetfile "oculink.kicad_sch")
		(attr smd)
		(fp_rect
			(start -0.925 0.47)
			(end 0.925 -0.47)
			(stroke
				(width 0.05)
				(type default)
			)
			(fill no)
			(layer "B.CrtYd")
		)
		(fp_rect
			(start -0.5 0.25)
			(end 0.5 -0.25)
			(stroke
				(width 0.15)
				(type solid)
			)
			(fill no)
			(layer "B.Fab")
		)
		(pad "1" smd roundrect
			(at -0.48 0)
			(size 0.59 0.64)
			(layers "B.Cu" "B.Mask" "B.Paste")
			(roundrect_rratio 0.25)
			(net 201 "/OCuLink/~{CPRSNT_D0}")
			(pintype "passive")
			(teardrops
				(best_length_ratio 0.2)
				(max_length 1)
				(best_width_ratio 0.9)
				(max_width 2)
				(curved_edges yes)
				(filter_ratio 0.9)
				(enabled yes)
				(allow_two_segments yes)
				(prefer_zone_connections yes)
			)
		)
		(pad "2" smd roundrect
			(at 0.48 0)
			(size 0.59 0.64)
			(layers "B.Cu" "B.Mask" "B.Paste")
			(roundrect_rratio 0.25)
			(net 2 "+3V3")
			(pintype "passive")
			(teardrops
				(best_length_ratio 0.2)
				(max_length 1)
				(best_width_ratio 0.9)
				(max_width 2)
				(curved_edges yes)
				(filter_ratio 0.9)
				(enabled yes)
				(allow_two_segments yes)
				(prefer_zone_connections yes)
			)
		)
	)
	(footprint "antmicro-footprints:C_0603_1608Metric"
		(layer "B.Cu")
		(at 129.063 132.09 -90)
		(descr "Capacitor SMD 0603")
		(tags "capacitor 0603")
		(property "Reference" "C183"
			(at -6.98 1.713 90)
			(layer "B.SilkS")
			(effects
				(font
					(size 0.7 0.7)
					(thickness 0.15)
				)
				(justify left bottom mirror)
			)
		)
		(property "Value" "C_22u_16V_0603"
			(at -1.42757 -1.770288 90)
			(layer "B.Fab")
			(effects
				(font
					(size 0.7 0.7)
					(thickness 0.15)
				)
				(justify left bottom mirror)
			)
		)
		(property "Datasheet" "https://product.samsungsem.com/mlcc/CL10A226MO7JZN.do"
			(at 0 0 270)
			(layer "F.Fab")
			(hide yes)
			(effects
				(font
					(size 1.27 1.27)
					(thickness 0.15)
				)
			)
		)
		(property "Author" "Antmicro"
			(at -3.027 261.153 0)
			(layer "B.Fab")
			(hide yes)
			(effects
				(font
					(size 1 1)
					(thickness 0.15)
				)
				(justify mirror)
			)
		)
		(property "Dielectric" ""
			(at -3.027 261.153 0)
			(layer "B.Fab")
			(hide yes)
			(effects
				(font
					(size 1 1)
					(thickness 0.15)
				)
				(justify mirror)
			)
		)
		(property "License" "Apache-2.0"
			(at -3.027 261.153 0)
			(layer "B.Fab")
			(hide yes)
			(effects
				(font
					(size 1 1)
					(thickness 0.15)
				)
				(justify mirror)
			)
		)
		(property "MPN" "CL10A226MO7JZNC"
			(at -3.027 261.153 0)
			(layer "B.Fab")
			(hide yes)
			(effects
				(font
					(size 1 1)
					(thickness 0.15)
				)
				(justify mirror)
			)
		)
		(property "Manufacturer" "Samsung Electro-Mechanics"
			(at -3.027 261.153 0)
			(layer "B.Fab")
			(hide yes)
			(effects
				(font
					(size 1 1)
					(thickness 0.15)
				)
				(justify mirror)
			)
		)
		(property "Public" "False"
			(at -3.027 261.153 0)
			(layer "B.Fab")
			(hide yes)
			(effects
				(font
					(size 1 1)
					(thickness 0.15)
				)
				(justify mirror)
			)
		)
		(property "Val" "22u"
			(at -3.027 261.153 0)
			(layer "B.Fab")
			(hide yes)
			(effects
				(font
					(size 1 1)
					(thickness 0.15)
				)
				(justify mirror)
			)
		)
		(property "Voltage" "16V"
			(at -3.027 261.153 0)
			(layer "B.Fab")
			(hide yes)
			(effects
				(font
					(size 1 1)
					(thickness 0.15)
				)
				(justify mirror)
			)
		)
		(sheetname "KR to SFI #2")
		(sheetfile "kr_sfi.kicad_sch")
		(attr smd)
		(fp_line
			(start 0.15 0.4)
			(end -0.15 0.4)
			(stroke
				(width 0.15)
				(type solid)
			)
			(layer "B.SilkS")
		)
		(fp_line
			(start 0.15 -0.4)
			(end -0.15 -0.4)
			(stroke
				(width 0.15)
				(type solid)
			)
			(layer "B.SilkS")
		)
		(fp_rect
			(start -1.25 0.65)
			(end 1.25 -0.65)
			(stroke
				(width 0.05)
				(type solid)
			)
			(fill no)
			(layer "B.CrtYd")
		)
		(fp_rect
			(start -0.8 0.4)
			(end 0.8 -0.4)
			(stroke
				(width 0.15)
				(type solid)
			)
			(fill no)
			(layer "B.Fab")
		)
		(pad "1" smd roundrect
			(at -0.7 0 270)
			(size 0.8 1)
			(layers "B.Cu" "B.Mask" "B.Paste")
			(roundrect_rratio 0.2)
			(net 1 "GND")
			(pintype "passive")
			(teardrops
				(best_length_ratio 0.2)
				(max_length 1)
				(best_width_ratio 0.9)
				(max_width 2)
				(curved_edges yes)
				(filter_ratio 0.9)
				(enabled yes)
				(allow_two_segments yes)
				(prefer_zone_connections yes)
			)
		)
		(pad "2" smd roundrect
			(at 0.7 0 270)
			(size 0.8 1)
			(layers "B.Cu" "B.Mask" "B.Paste")
			(roundrect_rratio 0.2)
			(net 78 "+1V8")
			(pintype "passive")
			(teardrops
				(best_length_ratio 0.2)
				(max_length 1)
				(best_width_ratio 0.9)
				(max_width 2)
				(curved_edges yes)
				(filter_ratio 0.9)
				(enabled yes)
				(allow_two_segments yes)
				(prefer_zone_connections yes)
			)
		)
	)
)
